(kicad_pcb
	(version 20260206)
	(generator "pcbnew")
	(generator_version "10.0")
	(general
		(thickness 1.6)
		(legacy_teardrops no)
	)
	(paper "A4")
	(title_block
		(title "pdpb — Lightning_PDPB_BRD.brd")
		(comment 1 "Lightning (Wiwynn / Facebook NVMe JBOF) / footprints 531-537 of 1140")
	)
	(layers
		(0 "F.Cu" signal "TOP")
		(4 "In1.Cu" signal "L2GND")
		(6 "In2.Cu" signal "L3")
		(8 "In3.Cu" signal "L4VCC")
		(10 "In4.Cu" signal "L5VCC")
		(12 "In5.Cu" signal "L6")
		(14 "In6.Cu" signal "L7GND")
		(2 "B.Cu" signal "BOTTOM")
		(9 "F.Adhes" user "F.Adhesive")
		(11 "B.Adhes" user "B.Adhesive")
		(13 "F.Paste" user "Package Geometry/Pastemask Top")
		(15 "B.Paste" user "Package Geometry/Pastemask Bottom")
		(5 "F.SilkS" user "Ref Des/Silkscreen Top")
		(7 "B.SilkS" user "Ref Des/Silkscreen Bottom")
		(1 "F.Mask" user "Board Geometry/Soldermask Top")
		(3 "B.Mask" user "Board Geometry/Soldermask Bottom")
		(17 "Dwgs.User" user "User.Drawings")
		(19 "Cmts.User" user "User.Comments")
		(21 "Eco1.User" user "User.Eco1")
		(23 "Eco2.User" user "User.Eco2")
		(25 "Edge.Cuts" user "Board Geometry/Outline")
		(27 "Margin" user)
		(31 "F.CrtYd" user "Package Geometry/Place Bound Top")
		(29 "B.CrtYd" user "Package Geometry/Place Bound Bottom")
		(35 "F.Fab" user "Ref Des/Assembly Top")
		(33 "B.Fab" user "Ref Des/Assembly Bottom")
	)
	(footprint ""
		(layer "F.Cu")
		(at 85.8012 -101.2444 180)
		(property "Reference" "R9974"
			(at 0 0 180)
			(layer "F.SilkS")
			(hide yes)
			(effects
				(font
					(size 1.27 1.27)
				)
			)
		)
		(property "Value" "100R1F-GP"
			(at -3.3274 -1.3335 180)
			(unlocked yes)
			(layer "F.Fab")
			(hide yes)
			(effects
				(font
					(size 1.016 1.016)
					(thickness 0.1524)
				)
			)
		)
		(property "Device Type" "R0201H12"
			(at -3.3274 -2.8575 180)
			(unlocked yes)
			(layer "F.Fab")
			(hide yes)
			(effects
				(font
					(size 1.016 1.016)
					(thickness 0.1524)
				)
			)
		)
		(duplicate_pad_numbers_are_jumpers no)
		(fp_rect
			(start -0.2794 0.6477)
			(end 0.2794 -0.6477)
			(stroke
				(width 0)
				(type default)
			)
			(fill no)
			(layer "F.CrtYd")
		)
		(fp_rect
			(start -0.2794 0.6477)
			(end 0.2794 -0.6477)
			(stroke
				(width 0)
				(type default)
			)
			(fill no)
			(layer "F.Fab")
		)
		(pad "1" smd custom
			(at 0 -0.2794 180)
			(size 0.0762 0.0762)
			(layers "F.Cu" "F.Mask" "F.Paste")
			(net "PE_100M_CLK1_N")
			(options
				(clearance outline)
				(anchor circle)
			)
			(primitives
				(gr_poly
					(pts
						(arc
							(start 0.1524 -0.127)
							(mid 0.137521 -0.162921)
							(end 0.1016 -0.1778)
						)
						(arc
							(start -0.1016 -0.1778)
							(mid -0.137521 -0.162921)
							(end -0.1524 -0.127)
						)
						(arc
							(start -0.1524 0.127)
							(mid -0.137521 0.162921)
							(end -0.1016 0.1778)
						)
						(arc
							(start 0.1016 0.1778)
							(mid 0.137521 0.162921)
							(end 0.1524 0.127)
						)
					)
					(width 0)
					(fill yes)
				)
			)
		)
		(pad "2" smd custom
			(at 0 0.2794 180)
			(size 0.0762 0.0762)
			(layers "F.Cu" "F.Mask" "F.Paste")
			(net "PE_100M_CLK1_P")
			(options
				(clearance outline)
				(anchor circle)
			)
			(primitives
				(gr_poly
					(pts
						(arc
							(start 0.1524 -0.127)
							(mid 0.137521 -0.162921)
							(end 0.1016 -0.1778)
						)
						(arc
							(start -0.1016 -0.1778)
							(mid -0.137521 -0.162921)
							(end -0.1524 -0.127)
						)
						(arc
							(start -0.1524 0.127)
							(mid -0.137521 0.162921)
							(end -0.1016 0.1778)
						)
						(arc
							(start 0.1016 0.1778)
							(mid 0.137521 0.162921)
							(end 0.1524 0.127)
						)
					)
					(width 0)
					(fill yes)
				)
			)
		)
	)
	(footprint ""
		(layer "F.Cu")
		(at 38.354 -38.735 180)
		(property "Reference" "Q74"
			(at 0 0 180)
			(layer "F.SilkS")
			(hide yes)
			(effects
				(font
					(size 1.27 1.27)
				)
			)
		)
		(property "Value" "2N7002A-7-GP"
			(at 0.127 -8.9662 180)
			(unlocked yes)
			(layer "F.Fab")
			(hide yes)
			(effects
				(font
					(size 1.016 1.016)
					(thickness 0.1524)
				)
			)
		)
		(property "Device Type" "SOT23DGS2D4H48"
			(at 0.127 -10.4902 180)
			(unlocked yes)
			(layer "F.Fab")
			(hide yes)
			(effects
				(font
					(size 1.016 1.016)
					(thickness 0.1524)
				)
			)
		)
		(duplicate_pad_numbers_are_jumpers no)
		(fp_line
			(start 1.651 1.778)
			(end 1.651 -1.778)
			(stroke
				(width 0.1524)
				(type default)
			)
			(layer "F.SilkS")
		)
		(fp_line
			(start 1.651 -1.778)
			(end -1.651 -1.778)
			(stroke
				(width 0.1524)
				(type default)
			)
			(layer "F.SilkS")
		)
		(fp_line
			(start -1.651 1.778)
			(end 1.651 1.778)
			(stroke
				(width 0.1524)
				(type default)
			)
			(layer "F.SilkS")
		)
		(fp_line
			(start -1.651 -1.778)
			(end -1.651 1.778)
			(stroke
				(width 0.1524)
				(type default)
			)
			(layer "F.SilkS")
		)
		(fp_poly
			(pts
				(xy -1.778 1.8796) (xy -1.778 -1.8796) (xy 1.778 -1.8796) (xy 1.778 1.8796)
			)
			(stroke
				(width 0)
				(type default)
			)
			(fill no)
			(layer "F.CrtYd")
		)
		(fp_poly
			(pts
				(xy -1.778 1.8796) (xy -1.778 -1.8796) (xy 1.778 -1.8796) (xy 1.778 1.8796)
			)
			(stroke
				(width 0)
				(type default)
			)
			(fill no)
			(layer "F.Fab")
		)
		(pad "D" smd custom
			(at 0 -0.9525 180)
			(size 0.1905 0.1905)
			(layers "F.Cu" "F.Mask" "F.Paste")
			(net "SSD9_CLK0_OE_MOS_N")
			(options
				(clearance outline)
				(anchor circle)
			)
			(primitives
				(gr_poly
					(pts
						(arc
							(start -0.1778 0.5715)
							(mid -0.321484 0.511984)
							(end -0.381 0.3683)
						)
						(arc
							(start -0.381 -0.3683)
							(mid -0.321484 -0.511984)
							(end -0.1778 -0.5715)
						)
						(arc
							(start 0.1778 -0.5715)
							(mid 0.321484 -0.511984)
							(end 0.381 -0.3683)
						)
						(arc
							(start 0.381 0.3683)
							(mid 0.321484 0.511984)
							(end 0.1778 0.5715)
						)
					)
					(width 0)
					(fill yes)
				)
			)
		)
		(pad "G" smd custom
			(at -0.98425 0.9525 180)
			(size 0.1905 0.1905)
			(layers "F.Cu" "F.Mask" "F.Paste")
			(net "SSD9_CLK0_OE_R_N")
			(options
				(clearance outline)
				(anchor circle)
			)
			(primitives
				(gr_poly
					(pts
						(arc
							(start -0.1778 0.5715)
							(mid -0.321484 0.511984)
							(end -0.381 0.3683)
						)
						(arc
							(start -0.381 -0.3683)
							(mid -0.321484 -0.511984)
							(end -0.1778 -0.5715)
						)
						(arc
							(start 0.1778 -0.5715)
							(mid 0.321484 -0.511984)
							(end 0.381 -0.3683)
						)
						(arc
							(start 0.381 0.3683)
							(mid 0.321484 0.511984)
							(end 0.1778 0.5715)
						)
					)
					(width 0)
					(fill yes)
				)
			)
		)
		(pad "S" smd custom
			(at 0.98425 0.9525 180)
			(size 0.1905 0.1905)
			(layers "F.Cu" "F.Mask" "F.Paste")
			(net "GND")
			(options
				(clearance outline)
				(anchor circle)
			)
			(primitives
				(gr_poly
					(pts
						(arc
							(start -0.1778 0.5715)
							(mid -0.321484 0.511984)
							(end -0.381 0.3683)
						)
						(arc
							(start -0.381 -0.3683)
							(mid -0.321484 -0.511984)
							(end -0.1778 -0.5715)
						)
						(arc
							(start 0.1778 -0.5715)
							(mid 0.321484 -0.511984)
							(end 0.381 -0.3683)
						)
						(arc
							(start 0.381 0.3683)
							(mid 0.321484 0.511984)
							(end 0.1778 0.5715)
						)
					)
					(width 0)
					(fill yes)
				)
			)
		)
	)
	(footprint ""
		(layer "F.Cu")
		(at 225.552 -40.894 90)
		(property "Reference" "R9916"
			(at 0 0 90)
			(layer "F.SilkS")
			(hide yes)
			(effects
				(font
					(size 1.27 1.27)
				)
			)
		)
		(property "Value" "47KR2J-2-GP"
			(at 0.064008 -3.993896 90)
			(unlocked yes)
			(layer "F.Fab")
			(hide yes)
			(effects
				(font
					(size 1.016 1.016)
					(thickness 0.1524)
				)
			)
		)
		(property "Device Type" "R402H16"
			(at 0.064008 -5.517896 90)
			(unlocked yes)
			(layer "F.Fab")
			(hide yes)
			(effects
				(font
					(size 1.016 1.016)
					(thickness 0.1524)
				)
			)
		)
		(duplicate_pad_numbers_are_jumpers no)
		(fp_line
			(start 0.508 -0.9398)
			(end -0.508 -0.9398)
			(stroke
				(width 0.1524)
				(type default)
			)
			(layer "F.SilkS")
		)
		(fp_line
			(start -0.508 -0.9398)
			(end -0.508 0.9398)
			(stroke
				(width 0.1524)
				(type default)
			)
			(layer "F.SilkS")
		)
		(fp_rect
			(start -0.508 0.9398)
			(end 0.508 -0.9398)
			(stroke
				(width 0)
				(type default)
			)
			(fill no)
			(layer "F.CrtYd")
		)
		(fp_rect
			(start -0.508 0.9398)
			(end 0.508 -0.9398)
			(stroke
				(width 0)
				(type default)
			)
			(fill no)
			(layer "F.Fab")
		)
		(pad "1" smd custom
			(at 0 -0.4445 90)
			(size 0.1397 0.1397)
			(layers "F.Cu" "F.Mask" "F.Paste")
			(net "P3V3")
			(options
				(clearance outline)
				(anchor circle)
			)
			(primitives
				(gr_poly
					(pts
						(arc
							(start -0.1778 -0.2794)
							(mid -0.249642 -0.249642)
							(end -0.2794 -0.1778)
						)
						(arc
							(start -0.2794 0.1778)
							(mid -0.249642 0.249642)
							(end -0.1778 0.2794)
						)
						(arc
							(start 0.1778 0.2794)
							(mid 0.249642 0.249642)
							(end 0.2794 0.1778)
						)
						(arc
							(start 0.2794 -0.1778)
							(mid 0.249642 -0.249642)
							(end 0.1778 -0.2794)
						)
					)
					(width 0)
					(fill yes)
				)
			)
		)
		(pad "2" smd custom
			(at 0 0.4445 90)
			(size 0.1397 0.1397)
			(layers "F.Cu" "F.Mask" "F.Paste")
			(net "ATTN_LED_DR4_N")
			(options
				(clearance outline)
				(anchor circle)
			)
			(primitives
				(gr_poly
					(pts
						(arc
							(start -0.1778 -0.2794)
							(mid -0.249642 -0.249642)
							(end -0.2794 -0.1778)
						)
						(arc
							(start -0.2794 0.1778)
							(mid -0.249642 0.249642)
							(end -0.1778 0.2794)
						)
						(arc
							(start 0.1778 0.2794)
							(mid 0.249642 0.249642)
							(end 0.2794 0.1778)
						)
						(arc
							(start 0.2794 -0.1778)
							(mid 0.249642 -0.249642)
							(end 0.1778 -0.2794)
						)
					)
					(width 0)
					(fill yes)
				)
			)
		)
	)
	(footprint ""
		(layer "F.Cu")
		(at 99.949 -310.769)
		(property "Reference" "C8852"
			(at 0 0 0)
			(layer "F.SilkS")
			(hide yes)
			(effects
				(font
					(size 1.27 1.27)
				)
			)
		)
		(property "Value" "SCD1U16V2KX-3GP"
			(at 1.1811 -2.7051 0)
			(unlocked yes)
			(layer "F.Fab")
			(hide yes)
			(effects
				(font
					(size 1.016 1.016)
					(thickness 0.1524)
				)
			)
		)
		(property "Device Type" "C402H22"
			(at 1.1811 -4.2291 0)
			(unlocked yes)
			(layer "F.Fab")
			(hide yes)
			(effects
				(font
					(size 1.016 1.016)
					(thickness 0.1524)
				)
			)
		)
		(duplicate_pad_numbers_are_jumpers no)
		(fp_rect
			(start -0.4318 0.9525)
			(end 0.4318 -0.9525)
			(stroke
				(width 0)
				(type default)
			)
			(fill no)
			(layer "F.CrtYd")
		)
		(fp_rect
			(start -0.4318 0.9525)
			(end 0.4318 -0.9525)
			(stroke
				(width 0)
				(type default)
			)
			(fill no)
			(layer "F.Fab")
		)
		(pad "1" smd custom
			(at 0 -0.4445)
			(size 0.1524 0.1524)
			(layers "F.Cu" "F.Mask" "F.Paste")
			(net "VDD_IO_2")
			(options
				(clearance outline)
				(anchor circle)
			)
			(primitives
				(gr_poly
					(pts
						(arc
							(start 0.3048 -0.2032)
							(mid 0.275042 -0.275042)
							(end 0.2032 -0.3048)
						)
						(arc
							(start -0.2032 -0.3048)
							(mid -0.275042 -0.275042)
							(end -0.3048 -0.2032)
						)
						(arc
							(start -0.3048 0.2032)
							(mid -0.275042 0.275042)
							(end -0.2032 0.3048)
						)
						(arc
							(start 0.2032 0.3048)
							(mid 0.275042 0.275042)
							(end 0.3048 0.2032)
						)
					)
					(width 0)
					(fill yes)
				)
			)
		)
		(pad "2" smd custom
			(at 0 0.4445)
			(size 0.1524 0.1524)
			(layers "F.Cu" "F.Mask" "F.Paste")
			(net "GND")
			(options
				(clearance outline)
				(anchor circle)
			)
			(primitives
				(gr_poly
					(pts
						(arc
							(start 0.3048 -0.2032)
							(mid 0.275042 -0.275042)
							(end 0.2032 -0.3048)
						)
						(arc
							(start -0.2032 -0.3048)
							(mid -0.275042 -0.275042)
							(end -0.3048 -0.2032)
						)
						(arc
							(start -0.3048 0.2032)
							(mid -0.275042 0.275042)
							(end -0.2032 0.3048)
						)
						(arc
							(start 0.2032 0.3048)
							(mid 0.275042 0.275042)
							(end 0.3048 0.2032)
						)
					)
					(width 0)
					(fill yes)
				)
			)
		)
	)
	(footprint ""
		(layer "F.Cu")
		(at 81.788 -145.415 -90)
		(property "Reference" "R427"
			(at 0 0 270)
			(layer "F.SilkS")
			(hide yes)
			(effects
				(font
					(size 1.27 1.27)
				)
			)
		)
		(property "Value" "0R2J-2-GP"
			(at 0.064008 -3.993896 270)
			(unlocked yes)
			(layer "F.Fab")
			(hide yes)
			(effects
				(font
					(size 1.016 1.016)
					(thickness 0.1524)
				)
			)
		)
		(property "Device Type" "R402H16"
			(at 0.064008 -5.517896 270)
			(unlocked yes)
			(layer "F.Fab")
			(hide yes)
			(effects
				(font
					(size 1.016 1.016)
					(thickness 0.1524)
				)
			)
		)
		(duplicate_pad_numbers_are_jumpers no)
		(fp_line
			(start -0.508 -0.9398)
			(end -0.508 0.9398)
			(stroke
				(width 0.1524)
				(type default)
			)
			(layer "F.SilkS")
		)
		(fp_line
			(start 0.508 -0.9398)
			(end -0.508 -0.9398)
			(stroke
				(width 0.1524)
				(type default)
			)
			(layer "F.SilkS")
		)
		(fp_rect
			(start -0.508 0.9398)
			(end 0.508 -0.9398)
			(stroke
				(width 0)
				(type default)
			)
			(fill no)
			(layer "F.CrtYd")
		)
		(fp_rect
			(start -0.508 0.9398)
			(end 0.508 -0.9398)
			(stroke
				(width 0)
				(type default)
			)
			(fill no)
			(layer "F.Fab")
		)
		(pad "1" smd custom
			(at 0 -0.4445 270)
			(size 0.1397 0.1397)
			(layers "F.Cu" "F.Mask" "F.Paste")
			(net "BMC_I2C_SCL_BUF_8")
			(options
				(clearance outline)
				(anchor circle)
			)
			(primitives
				(gr_poly
					(pts
						(arc
							(start -0.1778 -0.2794)
							(mid -0.249642 -0.249642)
							(end -0.2794 -0.1778)
						)
						(arc
							(start -0.2794 0.1778)
							(mid -0.249642 0.249642)
							(end -0.1778 0.2794)
						)
						(arc
							(start 0.1778 0.2794)
							(mid 0.249642 0.249642)
							(end 0.2794 0.1778)
						)
						(arc
							(start 0.2794 -0.1778)
							(mid 0.249642 -0.249642)
							(end 0.1778 -0.2794)
						)
					)
					(width 0)
					(fill yes)
				)
			)
		)
		(pad "2" smd custom
			(at 0 0.4445 270)
			(size 0.1397 0.1397)
			(layers "F.Cu" "F.Mask" "F.Paste")
			(net "I2C8_SCL_R_SW_EU16")
			(options
				(clearance outline)
				(anchor circle)
			)
			(primitives
				(gr_poly
					(pts
						(arc
							(start -0.1778 -0.2794)
							(mid -0.249642 -0.249642)
							(end -0.2794 -0.1778)
						)
						(arc
							(start -0.2794 0.1778)
							(mid -0.249642 0.249642)
							(end -0.1778 0.2794)
						)
						(arc
							(start 0.1778 0.2794)
							(mid 0.249642 0.249642)
							(end 0.2794 0.1778)
						)
						(arc
							(start 0.2794 -0.1778)
							(mid 0.249642 -0.249642)
							(end 0.1778 -0.2794)
						)
					)
					(width 0)
					(fill yes)
				)
			)
		)
	)
	(footprint ""
		(layer "F.Cu")
		(at 85.471 -302.387 90)
		(property "Reference" "PR9038"
			(at 0 0 90)
			(layer "F.SilkS")
			(hide yes)
			(effects
				(font
					(size 1.27 1.27)
				)
			)
		)
		(property "Value" "4K7R2F-GP"
			(at 0.064008 -3.993896 90)
			(unlocked yes)
			(layer "F.Fab")
			(hide yes)
			(effects
				(font
					(size 1.016 1.016)
					(thickness 0.1524)
				)
			)
		)
		(property "Device Type" "R402H16"
			(at 0.064008 -5.517896 90)
			(unlocked yes)
			(layer "F.Fab")
			(hide yes)
			(effects
				(font
					(size 1.016 1.016)
					(thickness 0.1524)
				)
			)
		)
		(duplicate_pad_numbers_are_jumpers no)
		(fp_line
			(start 0.508 -0.9398)
			(end -0.508 -0.9398)
			(stroke
				(width 0.1524)
				(type default)
			)
			(layer "F.SilkS")
		)
		(fp_line
			(start -0.508 -0.9398)
			(end -0.508 0.9398)
			(stroke
				(width 0.1524)
				(type default)
			)
			(layer "F.SilkS")
		)
		(fp_rect
			(start -0.508 0.9398)
			(end 0.508 -0.9398)
			(stroke
				(width 0)
				(type default)
			)
			(fill no)
			(layer "F.CrtYd")
		)
		(fp_rect
			(start -0.508 0.9398)
			(end 0.508 -0.9398)
			(stroke
				(width 0)
				(type default)
			)
			(fill no)
			(layer "F.Fab")
		)
		(pad "1" smd custom
			(at 0 -0.4445 90)
			(size 0.1397 0.1397)
			(layers "F.Cu" "F.Mask" "F.Paste")
			(net "VDD_DIFF_2")
			(options
				(clearance outline)
				(anchor circle)
			)
			(primitives
				(gr_poly
					(pts
						(arc
							(start -0.1778 -0.2794)
							(mid -0.249642 -0.249642)
							(end -0.2794 -0.1778)
						)
						(arc
							(start -0.2794 0.1778)
							(mid -0.249642 0.249642)
							(end -0.1778 0.2794)
						)
						(arc
							(start 0.1778 0.2794)
							(mid 0.249642 0.249642)
							(end 0.2794 0.1778)
						)
						(arc
							(start 0.2794 -0.1778)
							(mid 0.249642 -0.249642)
							(end 0.1778 -0.2794)
						)
					)
					(width 0)
					(fill yes)
				)
			)
		)
		(pad "2" smd custom
			(at 0 0.4445 90)
			(size 0.1397 0.1397)
			(layers "F.Cu" "F.Mask" "F.Paste")
			(net "CLK_BUF_EU2_SMB_A0_TRI")
			(options
				(clearance outline)
				(anchor circle)
			)
			(primitives
				(gr_poly
					(pts
						(arc
							(start -0.1778 -0.2794)
							(mid -0.249642 -0.249642)
							(end -0.2794 -0.1778)
						)
						(arc
							(start -0.2794 0.1778)
							(mid -0.249642 0.249642)
							(end -0.1778 0.2794)
						)
						(arc
							(start 0.1778 0.2794)
							(mid 0.249642 0.249642)
							(end 0.2794 0.1778)
						)
						(arc
							(start 0.2794 -0.1778)
							(mid 0.249642 -0.249642)
							(end 0.1778 -0.2794)
						)
					)
					(width 0)
					(fill yes)
				)
			)
		)
	)
	(footprint ""
		(layer "F.Cu")
		(at 234.061 -40.64 -90)
		(property "Reference" "R9408"
			(at 0 0 270)
			(layer "F.SilkS")
			(hide yes)
			(effects
				(font
					(size 1.27 1.27)
				)
			)
		)
		(property "Value" "100R2J-2-GP"
			(at 0.064008 -3.993896 270)
			(unlocked yes)
			(layer "F.Fab")
			(hide yes)
			(effects
				(font
					(size 1.016 1.016)
					(thickness 0.1524)
				)
			)
		)
		(property "Device Type" "R402H14"
			(at 0.064008 -5.517896 270)
			(unlocked yes)
			(layer "F.Fab")
			(hide yes)
			(effects
				(font
					(size 1.016 1.016)
					(thickness 0.1524)
				)
			)
		)
		(duplicate_pad_numbers_are_jumpers no)
		(fp_line
			(start -0.508 -0.9398)
			(end -0.508 0.9398)
			(stroke
				(width 0.1524)
				(type default)
			)
			(layer "F.SilkS")
		)
		(fp_line
			(start 0.508 -0.9398)
			(end -0.508 -0.9398)
			(stroke
				(width 0.1524)
				(type default)
			)
			(layer "F.SilkS")
		)
		(fp_rect
			(start -0.508 0.9398)
			(end 0.508 -0.9398)
			(stroke
				(width 0)
				(type default)
			)
			(fill no)
			(layer "F.CrtYd")
		)
		(fp_rect
			(start -0.508 0.9398)
			(end 0.508 -0.9398)
			(stroke
				(width 0)
				(type default)
			)
			(fill no)
			(layer "F.Fab")
		)
		(pad "1" smd custom
			(at 0 -0.4445 270)
			(size 0.1397 0.1397)
			(layers "F.Cu" "F.Mask" "F.Paste")
			(net "P3V3")
			(options
				(clearance outline)
				(anchor circle)
			)
			(primitives
				(gr_poly
					(pts
						(arc
							(start -0.1778 -0.2794)
							(mid -0.249642 -0.249642)
							(end -0.2794 -0.1778)
						)
						(arc
							(start -0.2794 0.1778)
							(mid -0.249642 0.249642)
							(end -0.1778 0.2794)
						)
						(arc
							(start 0.1778 0.2794)
							(mid 0.249642 0.249642)
							(end 0.2794 0.1778)
						)
						(arc
							(start 0.2794 -0.1778)
							(mid 0.249642 -0.249642)
							(end 0.1778 -0.2794)
						)
					)
					(width 0)
					(fill yes)
				)
			)
		)
		(pad "2" smd custom
			(at 0 0.4445 270)
			(size 0.1397 0.1397)
			(layers "F.Cu" "F.Mask" "F.Paste")
			(net "DRV_ACT_4")
			(options
				(clearance outline)
				(anchor circle)
			)
			(primitives
				(gr_poly
					(pts
						(arc
							(start -0.1778 -0.2794)
							(mid -0.249642 -0.249642)
							(end -0.2794 -0.1778)
						)
						(arc
							(start -0.2794 0.1778)
							(mid -0.249642 0.249642)
							(end -0.1778 0.2794)
						)
						(arc
							(start 0.1778 0.2794)
							(mid 0.249642 0.249642)
							(end 0.2794 0.1778)
						)
						(arc
							(start 0.2794 -0.1778)
							(mid 0.249642 -0.249642)
							(end 0.1778 -0.2794)
						)
					)
					(width 0)
					(fill yes)
				)
			)
		)
	)
)
